(kicad_pcb
	(version 20221018)
	(generator pcbnew)
	(general
    (thickness 1.518)
  )
	(paper "A4")
	(title_block
    (title "Kria K26 Devboard")
    (date "2024-03-26")
    (rev "1.2.5")
    (comment 1 "www.antmicro.com")
    (comment 2 "Antmicro Ltd.")
		(comment 9 "footprints 290-297 of 660")
	)
	(layers
    (0 "F.Cu" mixed)
    (1 "In1.Cu" power)
    (2 "In2.Cu" mixed)
    (3 "In3.Cu" power)
    (4 "In4.Cu" mixed)
    (5 "In5.Cu" power)
    (6 "In6.Cu" mixed)
    (31 "B.Cu" power)
    (32 "B.Adhes" user "B.Adhesive")
    (33 "F.Adhes" user "F.Adhesive")
    (34 "B.Paste" user)
    (35 "F.Paste" user)
    (36 "B.SilkS" user "B.Silkscreen")
    (37 "F.SilkS" user "F.Silkscreen")
    (38 "B.Mask" user)
    (39 "F.Mask" user)
    (40 "Dwgs.User" user "User.Drawings")
    (41 "Cmts.User" user "User.Comments")
    (42 "Eco1.User" user "User.Eco1")
    (43 "Eco2.User" user "User.Eco2")
    (44 "Edge.Cuts" user)
    (45 "Margin" user)
    (46 "B.CrtYd" user "B.Courtyard")
    (47 "F.CrtYd" user "F.Courtyard")
    (48 "B.Fab" user)
    (49 "F.Fab" user)
  )
	(footprint "kria-k26-devboard-footprints:C_0402_1005Metric" (layer "F.Cu")
    (at 87.23 102.2 180)
    (descr "Capacitor SMD 0402")
    (tags "capacitor SMD 0402")
    (property "Author" "Antmicro")
    (property "Dielectric" "X5R")
    (property "License" "Apache-2.0")
    (property "MPN" "GRM155R61H104KE14D")
    (property "Manufacturer" "Murata")
    (property "Sheetfile" "k26_som.kicad_sch")
    (property "Sheetname" "Xilinx K26 SOM")
    (property "Val" "100n")
    (property "Voltage" "50V")
    (property "ki_description" " ")
    (attr smd)
    (fp_text reference "C118" (at 3.7 -0.34 180) (layer "F.SilkS")
        (effects (font (size 0.7 0.7) (thickness 0.15)) (justify left bottom))
    )
    (fp_text value "C_100n_0402" (at 0 1.4 180) (layer "F.Fab") hide
        (effects (font (size 0.7 0.7) (thickness 0.15)) (justify left bottom))
    )
    (fp_text user "License: Apache-2.0" (at -0.932 5.17 180) (layer "F.Fab") hide
        (effects (font (size 0.7 0.7) (thickness 0.15)) (justify left bottom))
    )
    (fp_text user "Author: Antmicro" (at -0.932 4.17 180) (layer "F.Fab") hide
        (effects (font (size 0.7 0.7) (thickness 0.15)) (justify left bottom))
    )
    (fp_text user "${REFERENCE}" (at -0.932 3.168 180) (layer "F.Fab") hide
        (effects (font (size 0.7 0.7) (thickness 0.15)) (justify left bottom))
    )
    (fp_rect (start -0.94 -0.47) (end 0.94 0.47)
      (stroke (width 0.05) (type solid)) (fill none) (layer "F.CrtYd"))
    (fp_rect (start -0.499 -0.249) (end 0.499 0.249)
      (stroke (width 0.15) (type solid)) (fill none) (layer "F.Fab"))
    (pad "1" smd roundrect (at -0.484 0 180) (size 0.59 0.64) (layers "F.Cu" "F.Paste" "F.Mask") (roundrect_rratio 0.25)
      (net 8 "SOM_5V0") (pintype "passive"))
    (pad "2" smd roundrect (at 0.484 0 180) (size 0.59 0.64) (layers "F.Cu" "F.Paste" "F.Mask") (roundrect_rratio 0.25)
      (net 1 "GND") (pintype "passive"))
  )
	(footprint "kria-k26-devboard-footprints:C_0402_1005Metric" (layer "F.Cu")
    (at 87.23 101.2 180)
    (descr "Capacitor SMD 0402")
    (tags "capacitor SMD 0402")
    (property "Author" "Antmicro")
    (property "Dielectric" "")
    (property "License" "Apache-2.0")
    (property "MPN" "C1005X6S1A105K050BC")
    (property "Manufacturer" "TDK")
    (property "Sheetfile" "k26_som.kicad_sch")
    (property "Sheetname" "Xilinx K26 SOM")
    (property "Val" "1u")
    (property "Voltage" "")
    (property "ki_description" " ")
    (attr smd)
    (fp_text reference "C117" (at 3.7 -0.34 180) (layer "F.SilkS")
        (effects (font (size 0.7 0.7) (thickness 0.15)) (justify left bottom))
    )
    (fp_text value "C_1u_0402" (at 0 1.4 180) (layer "F.Fab") hide
        (effects (font (size 0.7 0.7) (thickness 0.15)) (justify left bottom))
    )
    (fp_text user "Author: Antmicro" (at -0.932 4.17 180) (layer "F.Fab") hide
        (effects (font (size 0.7 0.7) (thickness 0.15)) (justify left bottom))
    )
    (fp_text user "${REFERENCE}" (at -0.932 3.168 180) (layer "F.Fab") hide
        (effects (font (size 0.7 0.7) (thickness 0.15)) (justify left bottom))
    )
    (fp_text user "License: Apache-2.0" (at -0.932 5.17 180) (layer "F.Fab") hide
        (effects (font (size 0.7 0.7) (thickness 0.15)) (justify left bottom))
    )
    (fp_rect (start -0.94 -0.47) (end 0.94 0.47)
      (stroke (width 0.05) (type solid)) (fill none) (layer "F.CrtYd"))
    (fp_rect (start -0.499 -0.249) (end 0.499 0.249)
      (stroke (width 0.15) (type solid)) (fill none) (layer "F.Fab"))
    (pad "1" smd roundrect (at -0.484 0 180) (size 0.59 0.64) (layers "F.Cu" "F.Paste" "F.Mask") (roundrect_rratio 0.25)
      (net 8 "SOM_5V0") (pintype "passive"))
    (pad "2" smd roundrect (at 0.484 0 180) (size 0.59 0.64) (layers "F.Cu" "F.Paste" "F.Mask") (roundrect_rratio 0.25)
      (net 1 "GND") (pintype "passive"))
  )
	(footprint "kria-k26-devboard-footprints:C_0805_2012Metric" (layer "F.Cu")
    (at 86.2 99.65 180)
    (descr "Capacitor SMD 0805")
    (tags "capacitor SMD 0805")
    (property "Author" "Antmicro")
    (property "Dielectric" "")
    (property "License" "Apache-2.0")
    (property "MPN" "C0805C476M9PACTU")
    (property "Manufacturer" "KEMET")
    (property "Sheetfile" "k26_som.kicad_sch")
    (property "Sheetname" "Xilinx K26 SOM")
    (property "Val" "47u")
    (property "Voltage" "")
    (property "ki_description" " ")
    (attr smd)
    (fp_text reference "C115" (at 4.55 -0.36 180) (layer "F.SilkS")
        (effects (font (size 0.7 0.7) (thickness 0.15)) (justify left bottom))
    )
    (fp_text value "C_47u_0805" (at 0 1.947 180) (layer "F.Fab") hide
        (effects (font (size 0.7 0.7) (thickness 0.15)) (justify left bottom))
    )
    (fp_text user "License: Apache-2.0" (at -1.9 4.947 180) (layer "F.Fab") hide
        (effects (font (size 0.7 0.7) (thickness 0.15)) (justify left bottom))
    )
    (fp_text user "${REFERENCE}" (at -1.9 3.947 180) (layer "F.Fab") hide
        (effects (font (size 0.7 0.7) (thickness 0.15)) (justify left bottom))
    )
    (fp_text user "Author: Antmicro" (at -1.9 5.947 180) (layer "F.Fab") hide
        (effects (font (size 0.7 0.7) (thickness 0.15)) (justify left bottom))
    )
    (fp_line (start -0.3 -0.8) (end 0.3 -0.8)
      (stroke (width 0.15) (type solid)) (layer "F.SilkS"))
    (fp_line (start -0.3 0.8) (end 0.3 0.8)
      (stroke (width 0.15) (type solid)) (layer "F.SilkS"))
    (fp_rect (start -1.9 -0.93) (end 1.9 0.93)
      (stroke (width 0.05) (type solid)) (fill none) (layer "F.CrtYd"))
    (fp_rect (start -0.95 -0.675) (end 0.95 0.675)
      (stroke (width 0.15) (type solid)) (fill none) (layer "F.Fab"))
    (pad "1" smd rect (at -1.05 0 180) (size 1.2 1.2) (layers "F.Cu" "F.Paste" "F.Mask")
      (net 8 "SOM_5V0") (pintype "passive"))
    (pad "2" smd rect (at 1.05 0 180) (size 1.2 1.2) (layers "F.Cu" "F.Paste" "F.Mask")
      (net 1 "GND") (pintype "passive"))
  )
	(footprint "kria-k26-devboard-footprints:TP_SMD_0.75mm" (layer "F.Cu")
    (at 113.393934 91.550736)
    (property "Author" "Antmicro")
    (property "License" "Apache-2.0")
    (property "MPN" "")
    (property "Manufacturer" "")
    (property "Sheetfile" "usb.kicad_sch")
    (property "Sheetname" "USB")
    (property "ki_description" "Test Point 0.75mm")
    (attr exclude_from_pos_files)
    (fp_text reference "TP11" (at 0.246066 2.999264 90) (layer "F.SilkS")
        (effects (font (size 0.7 0.7) (thickness 0.15)) (justify left bottom))
    )
    (fp_text value "TP_0.75mm_SMD" (at 0 1.2) (layer "F.Fab") hide
        (effects (font (size 0.7 0.7) (thickness 0.15)) (justify left bottom))
    )
    (fp_text user "License: Apache-2.0" (at -0.4 5.101) (layer "F.Fab") hide
        (effects (font (size 0.7 0.7) (thickness 0.15)) (justify left bottom))
    )
    (fp_text user "${REFERENCE}" (at -0.4 2.7) (layer "F.Fab") hide
        (effects (font (size 0.7 0.7) (thickness 0.15)) (justify left bottom))
    )
    (fp_text user "Author: Antmicro" (at -0.4 3.901) (layer "F.Fab") hide
        (effects (font (size 0.7 0.7) (thickness 0.15)) (justify left bottom))
    )
    (pad "1" smd circle (at 0 0) (size 0.75 0.75) (layers "F.Cu" "F.Mask")
      (net 666 "Net-(U17-PF26)") (pinfunction "1") (pintype "passive"))
  )
	(footprint "kria-k26-devboard-footprints:TP_SMD_0.75mm" (layer "F.Cu")
    (at 114.118153 92.276086)
    (property "Author" "Antmicro")
    (property "License" "Apache-2.0")
    (property "MPN" "")
    (property "Manufacturer" "")
    (property "Sheetfile" "usb.kicad_sch")
    (property "Sheetname" "USB")
    (property "ki_description" "Test Point 0.75mm")
    (attr exclude_from_pos_files)
    (fp_text reference "TP12" (at 0.441847 2.993914 90) (layer "F.SilkS")
        (effects (font (size 0.7 0.7) (thickness 0.15)) (justify left bottom))
    )
    (fp_text value "TP_0.75mm_SMD" (at 0 1.2) (layer "F.Fab") hide
        (effects (font (size 0.7 0.7) (thickness 0.15)) (justify left bottom))
    )
    (fp_text user "${REFERENCE}" (at -0.4 2.7) (layer "F.Fab") hide
        (effects (font (size 0.7 0.7) (thickness 0.15)) (justify left bottom))
    )
    (fp_text user "License: Apache-2.0" (at -0.4 5.101) (layer "F.Fab") hide
        (effects (font (size 0.7 0.7) (thickness 0.15)) (justify left bottom))
    )
    (fp_text user "Author: Antmicro" (at -0.4 3.901) (layer "F.Fab") hide
        (effects (font (size 0.7 0.7) (thickness 0.15)) (justify left bottom))
    )
    (pad "1" smd circle (at 0 0) (size 0.75 0.75) (layers "F.Cu" "F.Mask")
      (net 667 "Net-(U17-PF27)") (pinfunction "1") (pintype "passive"))
  )
	(footprint "kria-k26-devboard-footprints:PinHeader_1x2_P2.54mm_Drill1.02mm" (layer "F.Cu")
    (at 109.35 83.9 180)
    (property "Author" "Antmicro")
    (property "License" "Apache-2.0")
    (property "MPN" "M20-9990246")
    (property "Manufacturer" "Harwin")
    (property "Sheetfile" "k26_som.kicad_sch")
    (property "Sheetname" "Xilinx K26 SOM")
    (attr through_hole)
    (fp_text reference "J6" (at 5.46 -1.37 180) (layer "F.SilkS")
        (effects (font (size 0.7 0.7) (thickness 0.15)) (justify left bottom))
    )
    (fp_text value "PinHeader_1x2_P2.54mm_Drill1.02mm" (at 0 2.6 180) (layer "F.Fab") hide
        (effects (font (size 0.7 0.7) (thickness 0.15)) (justify left bottom))
    )
    (fp_text user "${REFERENCE}" (at -1.6 7 180) (layer "F.Fab") hide
        (effects (font (size 0.7 0.7) (thickness 0.15)) (justify left bottom))
    )
    (fp_text user "Author: Antmicro" (at -1.6 4.6 180) (layer "F.Fab") hide
        (effects (font (size 0.7 0.7) (thickness 0.15)) (justify left bottom))
    )
    (fp_text user "License: Apache-2.0" (at -1.6 5.8 180) (layer "F.Fab") hide
        (effects (font (size 0.7 0.7) (thickness 0.15)) (justify left bottom))
    )
    (fp_line (start -1.401 -1.401) (end -1.401 -0.902)
      (stroke (width 0.15) (type solid)) (layer "F.SilkS"))
    (fp_line (start -1.401 -1.401) (end -0.902 -1.401)
      (stroke (width 0.15) (type solid)) (layer "F.SilkS"))
    (fp_line (start -1.401 1.398) (end -1.401 0.9)
      (stroke (width 0.15) (type solid)) (layer "F.SilkS"))
    (fp_line (start -1.401 1.398) (end -0.902 1.398)
      (stroke (width 0.15) (type solid)) (layer "F.SilkS"))
    (fp_line (start 3.898 -1.401) (end 3.398 -1.401)
      (stroke (width 0.15) (type solid)) (layer "F.SilkS"))
    (fp_line (start 3.898 -1.401) (end 3.898 -0.902)
      (stroke (width 0.15) (type solid)) (layer "F.SilkS"))
    (fp_line (start 3.898 1.398) (end 3.398 1.398)
      (stroke (width 0.15) (type solid)) (layer "F.SilkS"))
    (fp_line (start 3.898 1.398) (end 3.898 0.9)
      (stroke (width 0.15) (type solid)) (layer "F.SilkS"))
    (fp_rect (start -1.51 -1.51) (end 4.01 1.51)
      (stroke (width 0.05) (type solid)) (fill none) (layer "F.CrtYd"))
    (fp_line (start -1.27 -1.27) (end 3.809 -1.27)
      (stroke (width 0.15) (type solid)) (layer "F.Fab"))
    (fp_line (start -1.27 1.269) (end -1.27 -1.27)
      (stroke (width 0.15) (type solid)) (layer "F.Fab"))
    (fp_line (start -1.27 1.269) (end 3.809 1.269)
      (stroke (width 0.15) (type solid)) (layer "F.Fab"))
    (fp_line (start 3.809 1.269) (end 3.809 -1.27)
      (stroke (width 0.15) (type solid)) (layer "F.Fab"))
    (pad "1" thru_hole rect (at 0 0 180) (size 1.7 1.7) (drill 1.02) (layers "*.Cu" "*.Mask")
      (net 245 "Net-(FB2-Pad2)") (pintype "passive"))
    (pad "2" thru_hole circle (at 2.539 0.02 180) (size 1.7 1.7) (drill 1.02) (layers "*.Cu" "*.Mask")
      (net 244 "Net-(FB1-Pad2)") (pintype "passive"))
  )
	(footprint "kria-k26-devboard-footprints:R_0402_1005Metric" (layer "F.Cu")
    (at 97.725 116.6)
    (descr "Resistor SMD 0402")
    (tags "resistor SMD 0402")
    (property "Author" "Antmicro")
    (property "License" "Apache-2.0")
    (property "MPN" "CR0402-FX-33R0GLF")
    (property "Manufacturer" "Bourns")
    (property "Sheetfile" "sd-3-card.kicad_sch")
    (property "Sheetname" "SD 3.0 card")
    (property "Tolerance" "1%")
    (property "Val" "33R")
    (property "ki_description" "33R resistor in 0402 package with 1% tolerance")
    (attr smd)
    (fp_text reference "R13" (at -1.115 -1.5) (layer "F.SilkS")
        (effects (font (size 0.7 0.7) (thickness 0.15)) (justify left bottom))
    )
    (fp_text value "R_33R_0402" (at 0 1.4) (layer "F.Fab") hide
        (effects (font (size 0.7 0.7) (thickness 0.15)) (justify left bottom))
    )
    (fp_text user "License: Apache-2.0" (at -0.95 5.169) (layer "F.Fab") hide
        (effects (font (size 0.7 0.7) (thickness 0.15)) (justify left bottom))
    )
    (fp_text user "Author: Antmicro" (at -0.95 4.169) (layer "F.Fab") hide
        (effects (font (size 0.7 0.7) (thickness 0.15)) (justify left bottom))
    )
    (fp_text user "${REFERENCE}" (at -0.95 3.168) (layer "F.Fab") hide
        (effects (font (size 0.7 0.7) (thickness 0.15)) (justify left bottom))
    )
    (fp_rect (start -0.93 -0.47) (end 0.93 0.47)
      (stroke (width 0.05) (type solid)) (fill none) (layer "F.CrtYd"))
    (fp_rect (start -0.5 -0.25) (end 0.5 0.25)
      (stroke (width 0.15) (type solid)) (fill none) (layer "F.Fab"))
    (pad "1" smd roundrect (at -0.485 0) (size 0.59 0.64) (layers "F.Cu" "F.Paste" "F.Mask") (roundrect_rratio 0.25)
      (net 110 "/SD 3.0 card/MIO50") (pintype "passive"))
    (pad "2" smd roundrect (at 0.485 0) (size 0.59 0.64) (layers "F.Cu" "F.Paste" "F.Mask") (roundrect_rratio 0.25)
      (net 435 "Net-(U5-CMD_{A})") (pintype "passive"))
  )
	(footprint "kria-k26-devboard-footprints:R_0402_1005Metric" (layer "F.Cu")
    (at 97.725 115.65)
    (descr "Resistor SMD 0402")
    (tags "resistor SMD 0402")
    (property "Author" "Antmicro")
    (property "License" "Apache-2.0")
    (property "MPN" "CR0402-FX-33R0GLF")
    (property "Manufacturer" "Bourns")
    (property "Sheetfile" "sd-3-card.kicad_sch")
    (property "Sheetname" "SD 3.0 card")
    (property "Tolerance" "1%")
    (property "Val" "33R")
    (property "ki_description" "33R resistor in 0402 package with 1% tolerance")
    (attr smd)
    (fp_text reference "R14" (at -1.115 -1.5) (layer "F.SilkS")
        (effects (font (size 0.7 0.7) (thickness 0.15)) (justify left bottom))
    )
    (fp_text value "R_33R_0402" (at 0 1.4) (layer "F.Fab") hide
        (effects (font (size 0.7 0.7) (thickness 0.15)) (justify left bottom))
    )
    (fp_text user "Author: Antmicro" (at -0.95 4.169) (layer "F.Fab") hide
        (effects (font (size 0.7 0.7) (thickness 0.15)) (justify left bottom))
    )
    (fp_text user "${REFERENCE}" (at -0.95 3.168) (layer "F.Fab") hide
        (effects (font (size 0.7 0.7) (thickness 0.15)) (justify left bottom))
    )
    (fp_text user "License: Apache-2.0" (at -0.95 5.169) (layer "F.Fab") hide
        (effects (font (size 0.7 0.7) (thickness 0.15)) (justify left bottom))
    )
    (fp_rect (start -0.93 -0.47) (end 0.93 0.47)
      (stroke (width 0.05) (type solid)) (fill none) (layer "F.CrtYd"))
    (fp_rect (start -0.5 -0.25) (end 0.5 0.25)
      (stroke (width 0.15) (type solid)) (fill none) (layer "F.Fab"))
    (pad "1" smd roundrect (at -0.485 0) (size 0.59 0.64) (layers "F.Cu" "F.Paste" "F.Mask") (roundrect_rratio 0.25)
      (net 123 "/SD 3.0 card/MIO51") (pintype "passive"))
    (pad "2" smd roundrect (at 0.485 0) (size 0.59 0.64) (layers "F.Cu" "F.Paste" "F.Mask") (roundrect_rratio 0.25)
      (net 436 "Net-(U5-CLK_{A})") (pintype "passive"))
  )
)
